(kicad_pcb
	(version 20221018)
	(generator pcbnew)
	(general
    (thickness 1.518)
  )
	(paper "A4")
	(title_block
    (title "Kria K26 Devboard")
    (date "2024-03-26")
    (rev "1.2.5")
    (comment 1 "www.antmicro.com")
    (comment 2 "Antmicro Ltd.")
		(comment 9 "footprint 379 of 660 (J_SOM240_1), pads 206-242 of 242")
	)
	(layers
    (0 "F.Cu" mixed)
    (1 "In1.Cu" power)
    (2 "In2.Cu" mixed)
    (3 "In3.Cu" power)
    (4 "In4.Cu" mixed)
    (5 "In5.Cu" power)
    (6 "In6.Cu" mixed)
    (31 "B.Cu" power)
    (32 "B.Adhes" user "B.Adhesive")
    (33 "F.Adhes" user "F.Adhesive")
    (34 "B.Paste" user)
    (35 "F.Paste" user)
    (36 "B.SilkS" user "B.Silkscreen")
    (37 "F.SilkS" user "F.Silkscreen")
    (38 "B.Mask" user)
    (39 "F.Mask" user)
    (40 "Dwgs.User" user "User.Drawings")
    (41 "Cmts.User" user "User.Comments")
    (42 "Eco1.User" user "User.Eco1")
    (43 "Eco2.User" user "User.Eco2")
    (44 "Edge.Cuts" user)
    (45 "Margin" user)
    (46 "B.CrtYd" user "B.Courtyard")
    (47 "F.CrtYd" user "F.Courtyard")
    (48 "B.Fab" user)
    (49 "F.Fab" user)
  )
	(footprint "kria-k26-devboard-footprints:Conn_Plug_Samtec_ADM6_4x60_ADM6-60-01.5-L-4-2-A-TR"
    (layer "F.Cu")
    (at 91.5765 117.6215 -90)
    (property "Author" "Antmicro")
    (property "License" "Apache-2.0")
    (property "MPN" "ADM6-60-01.5-L-4-2-A-TR")
    (property "Manufacturer" "Samtec")
    (property "Sheetfile" "k26_som.kicad_sch")
    (property "Sheetname" "Xilinx K26 SOM")
    (property "ki_description" "Board to Board & Mezzanine Connectors 0.635 mm AcceleRate HD High-Density 4-Row Header 60P")
    (attr smd)
    (fp_text reference "J_SOM240_1" (at -13.8415 -3.7635 -90) (layer "F.SilkS")
        (effects (font (size 0.7 0.7) (thickness 0.15)) (justify left bottom))
    )
    (fp_text value "ADM6-60-01.5-L-4-2-A-TR" (at 0 3.7 -90) (layer "F.Fab") hide
        (effects (font (size 0.7 0.7) (thickness 0.15)) (justify left bottom))
    )
    (pad "D24" smd circle (at 4.127 1.749 270) (size 0.356 0.356) (layers "F.Cu" "F.Paste" "F.Mask")
      (net 473 "/Xilinx K26 SOM/PWRGD_FPD_M2C") (pinfunction "D24") (pintype "passive"))
    (pad "D25" smd circle (at 3.492 1.749 270) (size 0.356 0.356) (layers "F.Cu" "F.Paste" "F.Mask")
      (net 474 "/Xilinx K26 SOM/PWRGD_LPD_M2C") (pinfunction "D25") (pintype "passive"))
    (pad "D26" smd circle (at 2.857 1.749 270) (size 0.356 0.356) (layers "F.Cu" "F.Paste" "F.Mask")
      (net 475 "/Xilinx K26 SOM/PWR_GD_PL_M2C") (pinfunction "D26") (pintype "passive"))
    (pad "D27" smd circle (at 2.222 1.749 270) (size 0.356 0.356) (layers "F.Cu" "F.Paste" "F.Mask")
      (net 1 "GND") (pinfunction "D27") (pintype "passive"))
    (pad "D28" smd circle (at 1.587 1.749 270) (size 0.356 0.356) (layers "F.Cu" "F.Paste" "F.Mask")
      (net 476 "/Xilinx K26 SOM/MIO26") (pinfunction "D28") (pintype "passive"))
    (pad "D29" smd circle (at 0.952 1.749 270) (size 0.356 0.356) (layers "F.Cu" "F.Paste" "F.Mask")
      (net 116 "/Display Port/MIO27") (pinfunction "D29") (pintype "passive"))
    (pad "D30" smd circle (at 0.317 1.749 270) (size 0.356 0.356) (layers "F.Cu" "F.Paste" "F.Mask")
      (net 117 "/Display Port/MIO28") (pinfunction "D30") (pintype "passive"))
    (pad "D31" smd circle (at -0.318 1.749 270) (size 0.356 0.356) (layers "F.Cu" "F.Paste" "F.Mask")
      (net 1 "GND") (pinfunction "D31") (pintype "passive"))
    (pad "D32" smd circle (at -0.953 1.749 270) (size 0.356 0.356) (layers "F.Cu" "F.Paste" "F.Mask")
      (net 130 "/Reset logic/MIO44") (pinfunction "D32") (pintype "passive"))
    (pad "D33" smd circle (at -1.588 1.749 270) (size 0.356 0.356) (layers "F.Cu" "F.Paste" "F.Mask")
      (net 106 "/SD 3.0 card/MIO45") (pinfunction "D33") (pintype "passive"))
    (pad "D34" smd circle (at -2.223 1.749 270) (size 0.356 0.356) (layers "F.Cu" "F.Paste" "F.Mask")
      (net 118 "/SD 3.0 card/MIO46") (pinfunction "D34") (pintype "passive"))
    (pad "D35" smd circle (at -2.858 1.749 270) (size 0.356 0.356) (layers "F.Cu" "F.Paste" "F.Mask")
      (net 1 "GND") (pinfunction "D35") (pintype "passive"))
    (pad "D36" smd circle (at -3.493 1.749 270) (size 0.356 0.356) (layers "F.Cu" "F.Paste" "F.Mask")
      (net 46 "/USB/MIO52") (pinfunction "D36") (pintype "passive"))
    (pad "D37" smd circle (at -4.128 1.749 270) (size 0.356 0.356) (layers "F.Cu" "F.Paste" "F.Mask")
      (net 47 "/USB/MIO53") (pinfunction "D37") (pintype "passive"))
    (pad "D38" smd circle (at -4.763 1.749 270) (size 0.356 0.356) (layers "F.Cu" "F.Paste" "F.Mask")
      (net 48 "/USB/MIO54") (pinfunction "D38") (pintype "passive"))
    (pad "D39" smd circle (at -5.398 1.749 270) (size 0.356 0.356) (layers "F.Cu" "F.Paste" "F.Mask")
      (net 1 "GND") (pinfunction "D39") (pintype "passive"))
    (pad "D40" smd circle (at -6.033 1.749 270) (size 0.356 0.356) (layers "F.Cu" "F.Paste" "F.Mask")
      (net 25 "/Ethernet/MIO64") (pinfunction "D40") (pintype "passive"))
    (pad "D41" smd circle (at -6.668 1.749 270) (size 0.356 0.356) (layers "F.Cu" "F.Paste" "F.Mask")
      (net 35 "/Ethernet/MIO65") (pinfunction "D41") (pintype "passive"))
    (pad "D42" smd circle (at -7.303 1.749 270) (size 0.356 0.356) (layers "F.Cu" "F.Paste" "F.Mask")
      (net 36 "/Ethernet/MIO66") (pinfunction "D42") (pintype "passive"))
    (pad "D43" smd circle (at -7.938 1.749 270) (size 0.356 0.356) (layers "F.Cu" "F.Paste" "F.Mask")
      (net 1 "GND") (pinfunction "D43") (pintype "passive"))
    (pad "D44" smd circle (at -8.573 1.749 270) (size 0.356 0.356) (layers "F.Cu" "F.Paste" "F.Mask")
      (net 49 "/Ethernet/MIO76") (pinfunction "D44") (pintype "passive"))
    (pad "D45" smd circle (at -9.208 1.749 270) (size 0.356 0.356) (layers "F.Cu" "F.Paste" "F.Mask")
      (net 50 "/Ethernet/MIO77") (pinfunction "D45") (pintype "passive"))
    (pad "D46" smd circle (at -9.843 1.749 270) (size 0.356 0.356) (layers "F.Cu" "F.Paste" "F.Mask")
      (net 477 "unconnected-(J_SOM240_1-PadD46)") (pinfunction "D46") (pintype "passive+no_connect"))
    (pad "D47" smd circle (at -10.478 1.749 270) (size 0.356 0.356) (layers "F.Cu" "F.Paste" "F.Mask")
      (net 1 "GND") (pinfunction "D47") (pintype "passive"))
    (pad "D48" smd circle (at -11.113 1.749 270) (size 0.356 0.356) (layers "F.Cu" "F.Paste" "F.Mask")
      (net 1 "GND") (pinfunction "D48") (pintype "passive"))
    (pad "D49" smd circle (at -11.748 1.749 270) (size 0.356 0.356) (layers "F.Cu" "F.Paste" "F.Mask")
      (net 119 "/PCIE M2 key E /GTR_DP3_C2M_P") (pinfunction "D49") (pintype "passive"))
    (pad "D50" smd circle (at -12.383 1.749 270) (size 0.356 0.356) (layers "F.Cu" "F.Paste" "F.Mask")
      (net 120 "/PCIE M2 key E /GTR_DP3_C2M_N") (pinfunction "D50") (pintype "passive"))
    (pad "D51" smd circle (at -13.018 1.749 270) (size 0.356 0.356) (layers "F.Cu" "F.Paste" "F.Mask")
      (net 1 "GND") (pinfunction "D51") (pintype "passive"))
    (pad "D52" smd circle (at -13.653 1.749 270) (size 0.356 0.356) (layers "F.Cu" "F.Paste" "F.Mask")
      (net 1 "GND") (pinfunction "D52") (pintype "passive"))
    (pad "D53" smd circle (at -14.288 1.749 270) (size 0.356 0.356) (layers "F.Cu" "F.Paste" "F.Mask")
      (net 183 "/Clock distribution/GTR_REFCLK2_C2M_P") (pinfunction "D53") (pintype "passive"))
    (pad "D54" smd circle (at -14.923 1.749 270) (size 0.356 0.356) (layers "F.Cu" "F.Paste" "F.Mask")
      (net 184 "/Clock distribution/GTR_REFCLK2_C2M_N") (pinfunction "D54") (pintype "passive"))
    (pad "D55" smd circle (at -15.558 1.749 270) (size 0.356 0.356) (layers "F.Cu" "F.Paste" "F.Mask")
      (net 1 "GND") (pinfunction "D55") (pintype "passive"))
    (pad "D56" smd circle (at -16.193 1.749 270) (size 0.356 0.356) (layers "F.Cu" "F.Paste" "F.Mask")
      (net 1 "GND") (pinfunction "D56") (pintype "passive"))
    (pad "D57" smd circle (at -16.828 1.749 270) (size 0.356 0.356) (layers "F.Cu" "F.Paste" "F.Mask")
      (net 58 "/USB/GTR_DP2_M2C_P") (pinfunction "D57") (pintype "passive"))
    (pad "D58" smd circle (at -17.463 1.749 270) (size 0.356 0.356) (layers "F.Cu" "F.Paste" "F.Mask")
      (net 59 "/USB/GTR_DP2_M2C_N") (pinfunction "D58") (pintype "passive"))
    (pad "D59" smd circle (at -18.098 1.749 270) (size 0.356 0.356) (layers "F.Cu" "F.Paste" "F.Mask")
      (net 1 "GND") (pinfunction "D59") (pintype "passive"))
    (pad "D60" smd circle (at -18.733 1.749 270) (size 0.356 0.356) (layers "F.Cu" "F.Paste" "F.Mask")
      (net 8 "SOM_5V0") (pinfunction "D60") (pintype "passive"))
  )
)
